(kicad_pcb
	(version 20260206)
	(generator "pcbnew")
	(generator_version "10.0")
	(general
		(thickness 1.6)
		(legacy_teardrops no)
	)
	(paper "A4")
	(title_block
		(title "timecard-production-celestica-r4006 — R4006-B0001-02_R01.brd")
		(comment 1 "Time Appliance Project (Time Card) / footprints 1065-1069 of 1113")
	)
	(layers
		(0 "F.Cu" signal "TOP")
		(4 "In1.Cu" signal "L02_GND1")
		(6 "In2.Cu" signal "L03_SIG1")
		(8 "In3.Cu" signal "L04_GND2")
		(10 "In4.Cu" signal "L05_VCC1")
		(12 "In5.Cu" signal "L06_VCC2")
		(14 "In6.Cu" signal "L07_GND3")
		(16 "In7.Cu" signal "L08_SIG2")
		(18 "In8.Cu" signal "L09_GND4")
		(2 "B.Cu" signal "BOTTOM")
		(9 "F.Adhes" user "F.Adhesive")
		(11 "B.Adhes" user "B.Adhesive")
		(13 "F.Paste" user "Package Geometry/Pastemask Top")
		(15 "B.Paste" user "Package Geometry/Pastemask Bottom")
		(5 "F.SilkS" user "Ref Des/Silkscreen Top")
		(7 "B.SilkS" user "Ref Des/Silkscreen Bottom")
		(1 "F.Mask" user "Board Geometry/Soldermask Top")
		(3 "B.Mask" user "Board Geometry/Soldermask Bottom")
		(17 "Dwgs.User" user "User.Drawings")
		(19 "Cmts.User" user "User.Comments")
		(21 "Eco1.User" user "User.Eco1")
		(23 "Eco2.User" user "User.Eco2")
		(25 "Edge.Cuts" user "Board Geometry/Outline")
		(27 "Margin" user)
		(31 "F.CrtYd" user "Package Geometry/Place Bound Top")
		(29 "B.CrtYd" user "Package Geometry/Place Bound Bottom")
		(35 "F.Fab" user "Ref Des/Assembly Top")
		(33 "B.Fab" user "Ref Des/Assembly Bottom")
	)
	(footprint ""
		(layer "B.Cu")
		(at 18.415 -82.423 180)
		(property "Reference" "R478"
			(at -3.683 -0.42037 0)
			(unlocked yes)
			(layer "B.SilkS")
			(effects
				(font
					(size 0.7874 0.5842)
					(thickness 0.1524)
				)
				(justify mirror)
			)
		)
		(property "Value" "VAL*"
			(at -0.02032 2.13233 180)
			(unlocked yes)
			(layer "B.Fab")
			(hide yes)
			(effects
				(font
					(size 0.7874 0.5842)
					(thickness 0.1524)
				)
				(justify mirror)
			)
		)
		(property "Tolerance" "TOL*"
			(at -0.044704 3.05435 180)
			(unlocked yes)
			(layer "Cmts.User")
			(hide yes)
			(effects
				(font
					(size 0.7874 0.5842)
					(thickness 0.1524)
				)
				(justify mirror)
			)
		)
		(property "User Part Number" "PARTNUM*"
			(at -0.02032 4.024884 180)
			(unlocked yes)
			(layer "Cmts.User")
			(hide yes)
			(effects
				(font
					(size 0.7874 0.5842)
					(thickness 0.1524)
				)
				(justify mirror)
			)
		)
		(property "Device Type" "RESISTOR-G155-11003-01,100KOHMA"
			(at -0.008382 1.210564 180)
			(unlocked yes)
			(layer "B.Fab")
			(hide yes)
			(effects
				(font
					(size 0.7874 0.5842)
					(thickness 0.1524)
				)
				(justify mirror)
			)
		)
		(duplicate_pad_numbers_are_jumpers no)
		(fp_line
			(start 1.143 0.5588)
			(end -1.143 0.5588)
			(stroke
				(width 0.1)
				(type default)
			)
			(layer "B.SilkS")
		)
		(fp_line
			(start 1.143 -0.5588)
			(end 1.143 0.5588)
			(stroke
				(width 0.1)
				(type default)
			)
			(layer "B.SilkS")
		)
		(fp_line
			(start -1.143 0.5588)
			(end -1.143 -0.5588)
			(stroke
				(width 0.1)
				(type default)
			)
			(layer "B.SilkS")
		)
		(fp_line
			(start -1.143 -0.5588)
			(end 1.143 -0.5588)
			(stroke
				(width 0.1)
				(type default)
			)
			(layer "B.SilkS")
		)
		(fp_poly
			(pts
				(xy 1.143 0.5588) (xy -1.143 0.5588) (xy -1.143 -0.5588) (xy 1.143 -0.5588)
			)
			(stroke
				(width 0)
				(type default)
			)
			(fill no)
			(layer "B.CrtYd")
		)
		(fp_line
			(start 0.508 0.3048)
			(end -0.508 0.3048)
			(stroke
				(width 0.1)
				(type default)
			)
			(layer "B.Fab")
		)
		(fp_line
			(start 0.508 -0.3048)
			(end 0.508 0.3048)
			(stroke
				(width 0.1)
				(type default)
			)
			(layer "B.Fab")
		)
		(fp_line
			(start -0.508 0.3048)
			(end -0.508 -0.3048)
			(stroke
				(width 0.1)
				(type default)
			)
			(layer "B.Fab")
		)
		(fp_line
			(start -0.508 -0.3048)
			(end 0.508 -0.3048)
			(stroke
				(width 0.1)
				(type default)
			)
			(layer "B.Fab")
		)
		(pad "1" smd rect
			(at 0.5334 0)
			(size 0.7112 0.6096)
			(layers "B.Cu" "B.Mask" "B.Paste")
			(net "FT4232_I2C_SCL")
		)
		(pad "2" smd rect
			(at -0.5334 0)
			(size 0.7112 0.6096)
			(layers "B.Cu" "B.Mask" "B.Paste")
			(net "XP3R3V_FT4232")
		)
		(zone
			(layer "B.Cu")
			(hatch none 0.5)
			(connect_pads
				(clearance 0)
			)
			(min_thickness 0.25)
			(keepout
				(tracks not_allowed)
				(vias allowed)
				(pads allowed)
				(copperpour not_allowed)
				(footprints allowed)
			)
			(placement
				(enabled no)
				(sheetname "")
			)
			(fill
				(thermal_gap 0.5)
				(thermal_bridge_width 0.5)
				(island_removal_mode 0)
			)
			(polygon
				(pts
					(xy 18.3388 -82.7278) (xy 18.3388 -82.1182) (xy 18.4912 -82.1182) (xy 18.4912 -82.7278)
				)
			)
		)
		(zone
			(layer "B.Cu")
			(hatch none 0.5)
			(connect_pads
				(clearance 0)
			)
			(min_thickness 0.25)
			(keepout
				(tracks allowed)
				(vias not_allowed)
				(pads allowed)
				(copperpour not_allowed)
				(footprints allowed)
			)
			(placement
				(enabled no)
				(sheetname "")
			)
			(fill
				(thermal_gap 0.5)
				(thermal_bridge_width 0.5)
				(island_removal_mode 0)
			)
			(polygon
				(pts
					(xy 18.3388 -82.7278) (xy 18.3388 -82.1182) (xy 18.4912 -82.1182) (xy 18.4912 -82.7278)
				)
			)
		)
	)
	(footprint ""
		(layer "B.Cu")
		(at 17.7038 -40.6146 180)
		(property "Reference" "R144"
			(at 0.4318 1.12903 0)
			(unlocked yes)
			(layer "B.SilkS")
			(effects
				(font
					(size 0.7874 0.5842)
					(thickness 0.1524)
				)
				(justify mirror)
			)
		)
		(property "Value" "VAL*"
			(at -0.02032 2.13233 180)
			(unlocked yes)
			(layer "B.Fab")
			(hide yes)
			(effects
				(font
					(size 0.7874 0.5842)
					(thickness 0.1524)
				)
				(justify mirror)
			)
		)
		(property "Device Type" "RESISTOR-G155-133R0-01,33OHM,1%"
			(at -0.008382 1.210564 180)
			(unlocked yes)
			(layer "B.Fab")
			(hide yes)
			(effects
				(font
					(size 0.7874 0.5842)
					(thickness 0.1524)
				)
				(justify mirror)
			)
		)
		(property "User Part Number" "PARTNUM*"
			(at -0.02032 4.024884 180)
			(unlocked yes)
			(layer "Cmts.User")
			(hide yes)
			(effects
				(font
					(size 0.7874 0.5842)
					(thickness 0.1524)
				)
				(justify mirror)
			)
		)
		(property "Tolerance" "TOL*"
			(at -0.044704 3.05435 180)
			(unlocked yes)
			(layer "Cmts.User")
			(hide yes)
			(effects
				(font
					(size 0.7874 0.5842)
					(thickness 0.1524)
				)
				(justify mirror)
			)
		)
		(duplicate_pad_numbers_are_jumpers no)
		(fp_line
			(start 1.143 0.5588)
			(end -1.143 0.5588)
			(stroke
				(width 0.1)
				(type default)
			)
			(layer "B.SilkS")
		)
		(fp_line
			(start 1.143 -0.5588)
			(end 1.143 0.5588)
			(stroke
				(width 0.1)
				(type default)
			)
			(layer "B.SilkS")
		)
		(fp_line
			(start -1.143 0.5588)
			(end -1.143 -0.5588)
			(stroke
				(width 0.1)
				(type default)
			)
			(layer "B.SilkS")
		)
		(fp_line
			(start -1.143 -0.5588)
			(end 1.143 -0.5588)
			(stroke
				(width 0.1)
				(type default)
			)
			(layer "B.SilkS")
		)
		(fp_rect
			(start 1.143 0.5588)
			(end -1.143 -0.5588)
			(stroke
				(width 0)
				(type default)
			)
			(fill no)
			(layer "B.CrtYd")
		)
		(fp_line
			(start 0.508 0.3048)
			(end -0.508 0.3048)
			(stroke
				(width 0.1)
				(type default)
			)
			(layer "B.Fab")
		)
		(fp_line
			(start 0.508 -0.3048)
			(end 0.508 0.3048)
			(stroke
				(width 0.1)
				(type default)
			)
			(layer "B.Fab")
		)
		(fp_line
			(start -0.508 0.3048)
			(end -0.508 -0.3048)
			(stroke
				(width 0.1)
				(type default)
			)
			(layer "B.Fab")
		)
		(fp_line
			(start -0.508 -0.3048)
			(end 0.508 -0.3048)
			(stroke
				(width 0.1)
				(type default)
			)
			(layer "B.Fab")
		)
		(pad "1" smd rect
			(at 0.5334 0)
			(size 0.7112 0.6096)
			(layers "B.Cu" "B.Mask" "B.Paste")
			(net "PCA9546_I2C_SDA")
		)
		(pad "2" smd rect
			(at -0.5334 0)
			(size 0.7112 0.6096)
			(layers "B.Cu" "B.Mask" "B.Paste")
			(net "R_PCA9546_I2C_SDA")
		)
		(zone
			(layer "B.Cu")
			(hatch none 0.5)
			(connect_pads
				(clearance 0)
			)
			(min_thickness 0.25)
			(keepout
				(tracks allowed)
				(vias not_allowed)
				(pads allowed)
				(copperpour not_allowed)
				(footprints allowed)
			)
			(placement
				(enabled no)
				(sheetname "")
			)
			(fill
				(thermal_gap 0.5)
				(thermal_bridge_width 0.5)
				(island_removal_mode 0)
			)
			(polygon
				(pts
					(xy 17.6276 -40.9194) (xy 17.6276 -40.3098) (xy 17.78 -40.3098) (xy 17.78 -40.9194)
				)
			)
		)
	)
	(footprint ""
		(layer "B.Cu")
		(at 85.5472 -100.2538 180)
		(property "Reference" "SP2"
			(at 0.8382 -1.74117 0)
			(unlocked yes)
			(layer "B.SilkS")
			(effects
				(font
					(size 0.7874 0.5842)
					(thickness 0.1524)
				)
				(justify mirror)
			)
		)
		(property "Value" ""
			(at 0 0 0)
			(layer "B.Fab")
			(effects
				(font
					(size 1.27 1.27)
				)
				(justify mirror)
			)
		)
		(duplicate_pad_numbers_are_jumpers no)
		(fp_rect
			(start 0.1778 -0.3048)
			(end -0.1778 0.3048)
			(stroke
				(width 0)
				(type default)
			)
			(fill yes)
			(layer "B.Paste")
		)
		(fp_rect
			(start 0.2286 -0.3556)
			(end -0.2286 0.3556)
			(stroke
				(width 0)
				(type default)
			)
			(fill no)
			(layer "B.CrtYd")
		)
		(fp_line
			(start 0.1397 0.2413)
			(end 0.1397 -0.2413)
			(stroke
				(width 0.1)
				(type default)
			)
			(layer "B.Fab")
		)
		(fp_line
			(start 0.1397 -0.2413)
			(end -0.1397 -0.2413)
			(stroke
				(width 0.1)
				(type default)
			)
			(layer "B.Fab")
		)
		(fp_line
			(start -0.1397 0.2413)
			(end 0.1397 0.2413)
			(stroke
				(width 0.1)
				(type default)
			)
			(layer "B.Fab")
		)
		(fp_line
			(start -0.1397 -0.2413)
			(end -0.1397 0.2413)
			(stroke
				(width 0.1)
				(type default)
			)
			(layer "B.Fab")
		)
		(pad "1" smd rect
			(at 0.1143 0)
			(size 0.127 0.6096)
			(layers "B.Cu" "B.Mask" "B.Paste")
			(net "SG")
		)
		(pad "2" smd rect
			(at -0.1143 0)
			(size 0.127 0.6096)
			(layers "B.Cu" "B.Mask" "B.Paste")
			(net "XP3R3V_AGND")
		)
	)
	(footprint ""
		(layer "B.Cu")
		(at 112.141 -27.94 90)
		(property "Reference" "R358"
			(at -2.667 -0.16637 270)
			(unlocked yes)
			(layer "B.SilkS")
			(effects
				(font
					(size 0.7874 0.5842)
					(thickness 0.1524)
				)
				(justify mirror)
			)
		)
		(property "Value" "VAL*"
			(at -0.02032 2.13233 90)
			(unlocked yes)
			(layer "B.Fab")
			(hide yes)
			(effects
				(font
					(size 0.7874 0.5842)
					(thickness 0.1524)
				)
				(justify mirror)
			)
		)
		(property "Tolerance" "TOL*"
			(at -0.044704 3.05435 90)
			(unlocked yes)
			(layer "Cmts.User")
			(hide yes)
			(effects
				(font
					(size 0.7874 0.5842)
					(thickness 0.1524)
				)
				(justify mirror)
			)
		)
		(property "User Part Number" "PARTNUM*"
			(at -0.02032 4.024884 90)
			(unlocked yes)
			(layer "Cmts.User")
			(hide yes)
			(effects
				(font
					(size 0.7874 0.5842)
					(thickness 0.1524)
				)
				(justify mirror)
			)
		)
		(property "Device Type" "RESISTOR-G155-11002-01,10KOHM,A"
			(at -0.008382 1.210564 90)
			(unlocked yes)
			(layer "B.Fab")
			(hide yes)
			(effects
				(font
					(size 0.7874 0.5842)
					(thickness 0.1524)
				)
				(justify mirror)
			)
		)
		(duplicate_pad_numbers_are_jumpers no)
		(fp_line
			(start 1.143 -0.5588)
			(end 1.143 0.5588)
			(stroke
				(width 0.1)
				(type default)
			)
			(layer "B.SilkS")
		)
		(fp_line
			(start -1.143 -0.5588)
			(end 1.143 -0.5588)
			(stroke
				(width 0.1)
				(type default)
			)
			(layer "B.SilkS")
		)
		(fp_line
			(start 1.143 0.5588)
			(end -1.143 0.5588)
			(stroke
				(width 0.1)
				(type default)
			)
			(layer "B.SilkS")
		)
		(fp_line
			(start -1.143 0.5588)
			(end -1.143 -0.5588)
			(stroke
				(width 0.1)
				(type default)
			)
			(layer "B.SilkS")
		)
		(fp_poly
			(pts
				(xy 1.143 0.5588) (xy -1.143 0.5588) (xy -1.143 -0.5588) (xy 1.143 -0.5588)
			)
			(stroke
				(width 0)
				(type default)
			)
			(fill no)
			(layer "B.CrtYd")
		)
		(fp_line
			(start 0.508 -0.3048)
			(end 0.508 0.3048)
			(stroke
				(width 0.1)
				(type default)
			)
			(layer "B.Fab")
		)
		(fp_line
			(start -0.508 -0.3048)
			(end 0.508 -0.3048)
			(stroke
				(width 0.1)
				(type default)
			)
			(layer "B.Fab")
		)
		(fp_line
			(start 0.508 0.3048)
			(end -0.508 0.3048)
			(stroke
				(width 0.1)
				(type default)
			)
			(layer "B.Fab")
		)
		(fp_line
			(start -0.508 0.3048)
			(end -0.508 -0.3048)
			(stroke
				(width 0.1)
				(type default)
			)
			(layer "B.Fab")
		)
		(pad "1" smd rect
			(at 0.5334 0 270)
			(size 0.7112 0.6096)
			(layers "B.Cu" "B.Mask" "B.Paste")
			(net "MHZ200CLKP_CLKIN")
		)
		(pad "2" smd rect
			(at -0.5334 0 270)
			(size 0.7112 0.6096)
			(layers "B.Cu" "B.Mask" "B.Paste")
			(net "XP2R5V_FPGA")
		)
		(zone
			(layer "B.Cu")
			(hatch none 0.5)
			(connect_pads
				(clearance 0)
			)
			(min_thickness 0.25)
			(keepout
				(tracks allowed)
				(vias not_allowed)
				(pads allowed)
				(copperpour not_allowed)
				(footprints allowed)
			)
			(placement
				(enabled no)
				(sheetname "")
			)
			(fill
				(thermal_gap 0.5)
				(thermal_bridge_width 0.5)
				(island_removal_mode 0)
			)
			(polygon
				(pts
					(xy 112.4458 -28.0162) (xy 111.8362 -28.0162) (xy 111.8362 -27.8638) (xy 112.4458 -27.8638)
				)
			)
		)
		(zone
			(layer "B.Cu")
			(hatch none 0.5)
			(connect_pads
				(clearance 0)
			)
			(min_thickness 0.25)
			(keepout
				(tracks not_allowed)
				(vias allowed)
				(pads allowed)
				(copperpour not_allowed)
				(footprints allowed)
			)
			(placement
				(enabled no)
				(sheetname "")
			)
			(fill
				(thermal_gap 0.5)
				(thermal_bridge_width 0.5)
				(island_removal_mode 0)
			)
			(polygon
				(pts
					(xy 112.4458 -28.0162) (xy 111.8362 -28.0162) (xy 111.8362 -27.8638) (xy 112.4458 -27.8638)
				)
			)
		)
	)
	(footprint ""
		(layer "B.Cu")
		(at 27.686 -88.519 -90)
		(property "Reference" "L4"
			(at 2.286 0.03937 270)
			(unlocked yes)
			(layer "B.SilkS")
			(effects
				(font
					(size 0.7874 0.5842)
					(thickness 0.1524)
				)
				(justify mirror)
			)
		)
		(property "Value" "VAL*"
			(at -0.014732 2.526538 270)
			(unlocked yes)
			(layer "B.Fab")
			(hide yes)
			(effects
				(font
					(size 0.7874 0.5842)
					(thickness 0.000001)
				)
				(justify mirror)
			)
		)
		(property "Tolerance" "TOL*"
			(at -0.014732 3.503676 270)
			(unlocked yes)
			(layer "Cmts.User")
			(hide yes)
			(effects
				(font
					(size 0.7874 0.5842)
					(thickness 0.000001)
				)
				(justify mirror)
			)
		)
		(property "User Part Number" "PARTNUM*"
			(at -0.02794 4.480814 270)
			(unlocked yes)
			(layer "Cmts.User")
			(hide yes)
			(effects
				(font
					(size 0.7874 0.5842)
					(thickness 0.000001)
				)
				(justify mirror)
			)
		)
		(property "Device Type" "FERRITEBEAD-G191-10097-01,600OA"
			(at -0.014732 1.600708 270)
			(unlocked yes)
			(layer "B.Fab")
			(hide yes)
			(effects
				(font
					(size 0.7874 0.5842)
					(thickness 0.000001)
				)
				(justify mirror)
			)
		)
		(duplicate_pad_numbers_are_jumpers no)
		(fp_line
			(start -1.3208 0.7112)
			(end 1.3208 0.7112)
			(stroke
				(width 0.1)
				(type default)
			)
			(layer "B.SilkS")
		)
		(fp_line
			(start 1.3208 0.7112)
			(end 1.3208 -0.7112)
			(stroke
				(width 0.1)
				(type default)
			)
			(layer "B.SilkS")
		)
		(fp_line
			(start -1.3208 -0.7112)
			(end -1.3208 0.7112)
			(stroke
				(width 0.1)
				(type default)
			)
			(layer "B.SilkS")
		)
		(fp_line
			(start 1.3208 -0.7112)
			(end -1.3208 -0.7112)
			(stroke
				(width 0.1)
				(type default)
			)
			(layer "B.SilkS")
		)
		(fp_rect
			(start 1.3208 0.7112)
			(end -1.3208 -0.7112)
			(stroke
				(width 0)
				(type default)
			)
			(fill no)
			(layer "B.CrtYd")
		)
		(fp_line
			(start -0.8128 0.4572)
			(end 0.8128 0.4572)
			(stroke
				(width 0.1)
				(type default)
			)
			(layer "B.Fab")
		)
		(fp_line
			(start 0.8128 0.4572)
			(end 0.8128 -0.4572)
			(stroke
				(width 0.1)
				(type default)
			)
			(layer "B.Fab")
		)
		(fp_line
			(start -0.8128 -0.4572)
			(end -0.8128 0.4572)
			(stroke
				(width 0.1)
				(type default)
			)
			(layer "B.Fab")
		)
		(fp_line
			(start 0.8128 -0.4572)
			(end -0.8128 -0.4572)
			(stroke
				(width 0.1)
				(type default)
			)
			(layer "B.Fab")
		)
		(pad "1" smd rect
			(at 0.6858 0 90)
			(size 0.762 0.8636)
			(layers "B.Cu" "B.Mask" "B.Paste")
			(net "XP3R3V_FT4232")
		)
		(pad "2" smd rect
			(at -0.6858 0 90)
			(size 0.762 0.8636)
			(layers "B.Cu" "B.Mask" "B.Paste")
			(net "XP3R3V_VPLL")
		)
		(zone
			(layer "B.Cu")
			(hatch none 0.5)
			(connect_pads
				(clearance 0)
			)
			(min_thickness 0.25)
			(keepout
				(tracks not_allowed)
				(vias allowed)
				(pads allowed)
				(copperpour not_allowed)
				(footprints allowed)
			)
			(placement
				(enabled no)
				(sheetname "")
			)
			(fill
				(thermal_gap 0.5)
				(thermal_bridge_width 0.5)
				(island_removal_mode 0)
			)
			(polygon
				(pts
					(xy 27.2288 -88.3666) (xy 28.1432 -88.3666) (xy 28.1432 -88.6714) (xy 27.2288 -88.6714)
				)
			)
		)
		(zone
			(layer "B.Cu")
			(hatch none 0.5)
			(connect_pads
				(clearance 0)
			)
			(min_thickness 0.25)
			(keepout
				(tracks allowed)
				(vias not_allowed)
				(pads allowed)
				(copperpour not_allowed)
				(footprints allowed)
			)
			(placement
				(enabled no)
				(sheetname "")
			)
			(fill
				(thermal_gap 0.5)
				(thermal_bridge_width 0.5)
				(island_removal_mode 0)
			)
			(polygon
				(pts
					(xy 27.2288 -88.3666) (xy 28.1432 -88.3666) (xy 28.1432 -88.6714) (xy 27.2288 -88.6714)
				)
			)
		)
	)
)
